(kicad_pcb
	(version 20260206)
	(generator "pcbnew")
	(generator_version "10.0")
	(general
		(thickness 1.6)
		(legacy_teardrops no)
	)
	(paper "A4")
	(title_block
		(title "Bryce Canyon_R.DPB_16317-1_OCP.brd")
		(comment 1 "Bryce Canyon / footprints 1881-1887 of 2099")
	)
	(layers
		(0 "F.Cu" signal "TOP")
		(4 "In1.Cu" signal "L2GND")
		(6 "In2.Cu" signal "L3")
		(8 "In3.Cu" signal "L4VCC")
		(10 "In4.Cu" signal "L5VCC")
		(12 "In5.Cu" signal "L6")
		(14 "In6.Cu" signal "L7GND")
		(2 "B.Cu" signal "BOTTOM")
		(9 "F.Adhes" user "F.Adhesive")
		(11 "B.Adhes" user "B.Adhesive")
		(13 "F.Paste" user "Package Geometry/Pastemask Top")
		(15 "B.Paste" user "Package Geometry/Pastemask Bottom")
		(5 "F.SilkS" user "Ref Des/Silkscreen Top")
		(7 "B.SilkS" user "Ref Des/Silkscreen Bottom")
		(1 "F.Mask" user "Board Geometry/Soldermask Top")
		(3 "B.Mask" user "Board Geometry/Soldermask Bottom")
		(17 "Dwgs.User" user "User.Drawings")
		(19 "Cmts.User" user "User.Comments")
		(21 "Eco1.User" user "User.Eco1")
		(23 "Eco2.User" user "User.Eco2")
		(25 "Edge.Cuts" user "Board Geometry/Outline")
		(27 "Margin" user)
		(31 "F.CrtYd" user "Package Geometry/Place Bound Top")
		(29 "B.CrtYd" user "Package Geometry/Place Bound Bottom")
		(35 "F.Fab" user "Ref Des/Assembly Top")
		(33 "B.Fab" user "Ref Des/Assembly Bottom")
	)
	(footprint ""
		(layer "F.Cu")
		(at 16.764 -253.111 90)
		(property "Reference" "R905"
			(at 0 0 90)
			(layer "F.SilkS")
			(hide yes)
			(effects
				(font
					(size 1.27 1.27)
				)
			)
		)
		(property "Value" "4K7R2J-2-GP"
			(at 0.064008 -3.993896 90)
			(unlocked yes)
			(layer "F.Fab")
			(hide yes)
			(effects
				(font
					(size 1.016 1.016)
					(thickness 0.1524)
				)
			)
		)
		(property "Device Type" "R402H16"
			(at 0.064008 -5.517896 90)
			(unlocked yes)
			(layer "F.Fab")
			(hide yes)
			(effects
				(font
					(size 1.016 1.016)
					(thickness 0.1524)
				)
			)
		)
		(duplicate_pad_numbers_are_jumpers no)
		(fp_line
			(start 0.508 -0.9398)
			(end -0.508 -0.9398)
			(stroke
				(width 0.1524)
				(type default)
			)
			(layer "F.SilkS")
		)
		(fp_line
			(start -0.508 -0.9398)
			(end -0.508 0.9398)
			(stroke
				(width 0.1524)
				(type default)
			)
			(layer "F.SilkS")
		)
		(fp_rect
			(start -0.508 0.9398)
			(end 0.508 -0.9398)
			(stroke
				(width 0)
				(type default)
			)
			(fill no)
			(layer "F.CrtYd")
		)
		(fp_rect
			(start -0.508 0.9398)
			(end 0.508 -0.9398)
			(stroke
				(width 0)
				(type default)
			)
			(fill no)
			(layer "F.Fab")
		)
		(pad "1" smd custom
			(at 0 -0.4445 90)
			(size 0.1397 0.1397)
			(layers "F.Cu" "F.Mask" "F.Paste")
			(net "P12V_B")
			(options
				(clearance outline)
				(anchor circle)
			)
			(primitives
				(gr_poly
					(pts
						(arc
							(start -0.1778 -0.2794)
							(mid -0.249642 -0.249642)
							(end -0.2794 -0.1778)
						)
						(arc
							(start -0.2794 0.1778)
							(mid -0.249642 0.249642)
							(end -0.1778 0.2794)
						)
						(arc
							(start 0.1778 0.2794)
							(mid 0.249642 0.249642)
							(end 0.2794 0.1778)
						)
						(arc
							(start 0.2794 -0.1778)
							(mid 0.249642 -0.249642)
							(end 0.1778 -0.2794)
						)
					)
					(width 0)
					(fill yes)
				)
			)
		)
		(pad "2" smd custom
			(at 0 0.4445 90)
			(size 0.1397 0.1397)
			(layers "F.Cu" "F.Mask" "F.Paste")
			(net "SW_HDD_P0")
			(options
				(clearance outline)
				(anchor circle)
			)
			(primitives
				(gr_poly
					(pts
						(arc
							(start -0.1778 -0.2794)
							(mid -0.249642 -0.249642)
							(end -0.2794 -0.1778)
						)
						(arc
							(start -0.2794 0.1778)
							(mid -0.249642 0.249642)
							(end -0.1778 0.2794)
						)
						(arc
							(start 0.1778 0.2794)
							(mid 0.249642 0.249642)
							(end 0.2794 0.1778)
						)
						(arc
							(start 0.2794 -0.1778)
							(mid 0.249642 -0.249642)
							(end 0.1778 -0.2794)
						)
					)
					(width 0)
					(fill yes)
				)
			)
		)
	)
	(footprint ""
		(layer "F.Cu")
		(at 112.450118 -65.39992)
		(property "Reference" "LED16"
			(at 0 0 0)
			(layer "F.SilkS")
			(hide yes)
			(effects
				(font
					(size 1.27 1.27)
				)
			)
		)
		(property "Value" "LED-BY-19-GP"
			(at -2.132076 1.414018 0)
			(unlocked yes)
			(layer "F.Fab")
			(hide yes)
			(effects
				(font
					(size 1.016 1.016)
					(thickness 0.1524)
				)
			)
		)
		(property "Device Type" "LED-1615-4PH26"
			(at -2.132076 -0.109982 0)
			(unlocked yes)
			(layer "F.Fab")
			(hide yes)
			(effects
				(font
					(size 1.016 1.016)
					(thickness 0.1524)
				)
			)
		)
		(duplicate_pad_numbers_are_jumpers no)
		(fp_line
			(start -1.2954 0.254)
			(end -1.2954 1.6002)
			(stroke
				(width 0.508)
				(type default)
			)
			(layer "F.SilkS")
		)
		(fp_line
			(start -1.2954 1.6002)
			(end 1.2954 1.6002)
			(stroke
				(width 0.508)
				(type default)
			)
			(layer "F.SilkS")
		)
		(fp_line
			(start -1.1176 -1.4224)
			(end 1.1176 -1.4224)
			(stroke
				(width 0.1524)
				(type default)
			)
			(layer "F.SilkS")
		)
		(fp_line
			(start -1.1176 1.4224)
			(end -1.1176 -1.4224)
			(stroke
				(width 0.1524)
				(type default)
			)
			(layer "F.SilkS")
		)
		(fp_line
			(start 1.1176 -1.4224)
			(end 1.1176 1.4224)
			(stroke
				(width 0.1524)
				(type default)
			)
			(layer "F.SilkS")
		)
		(fp_line
			(start 1.1176 1.4224)
			(end -1.1176 1.4224)
			(stroke
				(width 0.1524)
				(type default)
			)
			(layer "F.SilkS")
		)
		(fp_line
			(start 1.2954 1.6002)
			(end 1.2954 0.254)
			(stroke
				(width 0.508)
				(type default)
			)
			(layer "F.SilkS")
		)
		(fp_rect
			(start -0.7493 0.8001)
			(end 0.7493 -0.8001)
			(stroke
				(width 0)
				(type default)
			)
			(fill no)
			(layer "F.CrtYd")
		)
		(fp_poly
			(pts
				(xy -1.3716 1.6764) (xy -1.3716 -1.6764) (xy 1.3716 -1.6764) (xy 1.3716 0.0635) (xy 0.7493 0.0635)
				(xy 0.7493 -0.8001) (xy -0.7493 -0.8001) (xy -0.7493 0.8001) (xy 0.7493 0.8001) (xy 0.7493 0.0762)
				(xy 1.3716 0.0762) (xy 1.3716 1.6764)
			)
			(stroke
				(width 0)
				(type default)
			)
			(fill no)
			(layer "F.CrtYd")
		)
		(fp_rect
			(start -1.3716 1.6764)
			(end 1.3716 -1.6764)
			(stroke
				(width 0)
				(type default)
			)
			(fill no)
			(layer "F.Fab")
		)
		(pad "1" smd rect
			(at 0.50038 -0.73025)
			(size 0.7112 0.8636)
			(layers "F.Cu" "F.Mask" "F.Paste")
			(net "DRV_ACT_15")
		)
		(pad "2" smd rect
			(at -0.50038 -0.73025)
			(size 0.7112 0.8636)
			(layers "F.Cu" "F.Mask" "F.Paste")
			(net "FLT_HDD15")
		)
		(pad "3" smd rect
			(at 0.50038 0.73025)
			(size 0.7112 0.8636)
			(layers "F.Cu" "F.Mask" "F.Paste")
			(net "DRV_ACT_15_N")
		)
		(pad "4" smd rect
			(at -0.50038 0.73025)
			(size 0.7112 0.8636)
			(layers "F.Cu" "F.Mask" "F.Paste")
			(net "FLT_HDD15_N")
		)
	)
	(footprint ""
		(layer "F.Cu")
		(at 251.4854 -211.201)
		(property "Reference" "C23"
			(at 0 0 0)
			(layer "F.SilkS")
			(hide yes)
			(effects
				(font
					(size 1.27 1.27)
				)
			)
		)
		(property "Value" "SCD1U16V2KX-3GP"
			(at 1.1811 -2.7051 0)
			(unlocked yes)
			(layer "F.Fab")
			(hide yes)
			(effects
				(font
					(size 1.016 1.016)
					(thickness 0.1524)
				)
			)
		)
		(property "Device Type" "C402H22"
			(at 1.1811 -4.2291 0)
			(unlocked yes)
			(layer "F.Fab")
			(hide yes)
			(effects
				(font
					(size 1.016 1.016)
					(thickness 0.1524)
				)
			)
		)
		(duplicate_pad_numbers_are_jumpers no)
		(fp_rect
			(start -0.4318 0.9525)
			(end 0.4318 -0.9525)
			(stroke
				(width 0)
				(type default)
			)
			(fill no)
			(layer "F.CrtYd")
		)
		(fp_rect
			(start -0.4318 0.9525)
			(end 0.4318 -0.9525)
			(stroke
				(width 0)
				(type default)
			)
			(fill no)
			(layer "F.Fab")
		)
		(pad "1" smd custom
			(at 0 -0.4445)
			(size 0.1524 0.1524)
			(layers "F.Cu" "F.Mask" "F.Paste")
			(net "P3V3_STBY_B")
			(options
				(clearance outline)
				(anchor circle)
			)
			(primitives
				(gr_poly
					(pts
						(arc
							(start 0.3048 -0.2032)
							(mid 0.275042 -0.275042)
							(end 0.2032 -0.3048)
						)
						(arc
							(start -0.2032 -0.3048)
							(mid -0.275042 -0.275042)
							(end -0.3048 -0.2032)
						)
						(arc
							(start -0.3048 0.2032)
							(mid -0.275042 0.275042)
							(end -0.2032 0.3048)
						)
						(arc
							(start 0.2032 0.3048)
							(mid 0.275042 0.275042)
							(end 0.3048 0.2032)
						)
					)
					(width 0)
					(fill yes)
				)
			)
		)
		(pad "2" smd custom
			(at 0 0.4445)
			(size 0.1524 0.1524)
			(layers "F.Cu" "F.Mask" "F.Paste")
			(net "GND")
			(options
				(clearance outline)
				(anchor circle)
			)
			(primitives
				(gr_poly
					(pts
						(arc
							(start 0.3048 -0.2032)
							(mid 0.275042 -0.275042)
							(end 0.2032 -0.3048)
						)
						(arc
							(start -0.2032 -0.3048)
							(mid -0.275042 -0.275042)
							(end -0.3048 -0.2032)
						)
						(arc
							(start -0.3048 0.2032)
							(mid -0.275042 0.275042)
							(end -0.2032 0.3048)
						)
						(arc
							(start 0.2032 0.3048)
							(mid 0.275042 0.275042)
							(end 0.3048 0.2032)
						)
					)
					(width 0)
					(fill yes)
				)
			)
		)
	)
	(footprint ""
		(layer "F.Cu")
		(at 50.4952 -9.9568 180)
		(property "Reference" "C364"
			(at 0 0 180)
			(layer "F.SilkS")
			(hide yes)
			(effects
				(font
					(size 1.27 1.27)
				)
			)
		)
		(property "Value" "SCD033U25V2KX-GP"
			(at 1.1811 -2.7051 180)
			(unlocked yes)
			(layer "F.Fab")
			(hide yes)
			(effects
				(font
					(size 1.016 1.016)
					(thickness 0.1524)
				)
			)
		)
		(property "Device Type" "C402H22"
			(at 1.1811 -4.2291 180)
			(unlocked yes)
			(layer "F.Fab")
			(hide yes)
			(effects
				(font
					(size 1.016 1.016)
					(thickness 0.1524)
				)
			)
		)
		(duplicate_pad_numbers_are_jumpers no)
		(fp_rect
			(start -0.4318 0.9525)
			(end 0.4318 -0.9525)
			(stroke
				(width 0)
				(type default)
			)
			(fill no)
			(layer "F.CrtYd")
		)
		(fp_rect
			(start -0.4318 0.9525)
			(end 0.4318 -0.9525)
			(stroke
				(width 0)
				(type default)
			)
			(fill no)
			(layer "F.Fab")
		)
		(pad "1" smd custom
			(at 0 -0.4445 180)
			(size 0.1524 0.1524)
			(layers "F.Cu" "F.Mask" "F.Paste")
			(net "P12V_B")
			(options
				(clearance outline)
				(anchor circle)
			)
			(primitives
				(gr_poly
					(pts
						(arc
							(start 0.3048 -0.2032)
							(mid 0.275042 -0.275042)
							(end 0.2032 -0.3048)
						)
						(arc
							(start -0.2032 -0.3048)
							(mid -0.275042 -0.275042)
							(end -0.3048 -0.2032)
						)
						(arc
							(start -0.3048 0.2032)
							(mid -0.275042 0.275042)
							(end -0.2032 0.3048)
						)
						(arc
							(start 0.2032 0.3048)
							(mid 0.275042 0.275042)
							(end 0.3048 0.2032)
						)
					)
					(width 0)
					(fill yes)
				)
			)
		)
		(pad "2" smd custom
			(at 0 0.4445 180)
			(size 0.1524 0.1524)
			(layers "F.Cu" "F.Mask" "F.Paste")
			(net "SW_HDD_N25")
			(options
				(clearance outline)
				(anchor circle)
			)
			(primitives
				(gr_poly
					(pts
						(arc
							(start 0.3048 -0.2032)
							(mid 0.275042 -0.275042)
							(end 0.2032 -0.3048)
						)
						(arc
							(start -0.2032 -0.3048)
							(mid -0.275042 -0.275042)
							(end -0.3048 -0.2032)
						)
						(arc
							(start -0.3048 0.2032)
							(mid -0.275042 0.275042)
							(end -0.2032 0.3048)
						)
						(arc
							(start 0.2032 0.3048)
							(mid 0.275042 0.275042)
							(end 0.3048 0.2032)
						)
					)
					(width 0)
					(fill yes)
				)
			)
		)
	)
	(footprint ""
		(layer "F.Cu")
		(at 315.149992 -65.39992)
		(property "Reference" "LED19"
			(at 0 0 0)
			(layer "F.SilkS")
			(hide yes)
			(effects
				(font
					(size 1.27 1.27)
				)
			)
		)
		(property "Value" "LED-BY-19-GP"
			(at -2.132076 1.414018 0)
			(unlocked yes)
			(layer "F.Fab")
			(hide yes)
			(effects
				(font
					(size 1.016 1.016)
					(thickness 0.1524)
				)
			)
		)
		(property "Device Type" "LED-1615-4PH26"
			(at -2.132076 -0.109982 0)
			(unlocked yes)
			(layer "F.Fab")
			(hide yes)
			(effects
				(font
					(size 1.016 1.016)
					(thickness 0.1524)
				)
			)
		)
		(duplicate_pad_numbers_are_jumpers no)
		(fp_line
			(start -1.2954 0.254)
			(end -1.2954 1.6002)
			(stroke
				(width 0.508)
				(type default)
			)
			(layer "F.SilkS")
		)
		(fp_line
			(start -1.2954 1.6002)
			(end 1.2954 1.6002)
			(stroke
				(width 0.508)
				(type default)
			)
			(layer "F.SilkS")
		)
		(fp_line
			(start -1.1176 -1.4224)
			(end 1.1176 -1.4224)
			(stroke
				(width 0.1524)
				(type default)
			)
			(layer "F.SilkS")
		)
		(fp_line
			(start -1.1176 1.4224)
			(end -1.1176 -1.4224)
			(stroke
				(width 0.1524)
				(type default)
			)
			(layer "F.SilkS")
		)
		(fp_line
			(start 1.1176 -1.4224)
			(end 1.1176 1.4224)
			(stroke
				(width 0.1524)
				(type default)
			)
			(layer "F.SilkS")
		)
		(fp_line
			(start 1.1176 1.4224)
			(end -1.1176 1.4224)
			(stroke
				(width 0.1524)
				(type default)
			)
			(layer "F.SilkS")
		)
		(fp_line
			(start 1.2954 1.6002)
			(end 1.2954 0.254)
			(stroke
				(width 0.508)
				(type default)
			)
			(layer "F.SilkS")
		)
		(fp_rect
			(start -0.7493 0.8001)
			(end 0.7493 -0.8001)
			(stroke
				(width 0)
				(type default)
			)
			(fill no)
			(layer "F.CrtYd")
		)
		(fp_poly
			(pts
				(xy -1.3716 1.6764) (xy -1.3716 -1.6764) (xy 1.3716 -1.6764) (xy 1.3716 0.0635) (xy 0.7493 0.0635)
				(xy 0.7493 -0.8001) (xy -0.7493 -0.8001) (xy -0.7493 0.8001) (xy 0.7493 0.8001) (xy 0.7493 0.0762)
				(xy 1.3716 0.0762) (xy 1.3716 1.6764)
			)
			(stroke
				(width 0)
				(type default)
			)
			(fill no)
			(layer "F.CrtYd")
		)
		(fp_rect
			(start -1.3716 1.6764)
			(end 1.3716 -1.6764)
			(stroke
				(width 0)
				(type default)
			)
			(fill no)
			(layer "F.Fab")
		)
		(pad "1" smd rect
			(at 0.50038 -0.73025)
			(size 0.7112 0.8636)
			(layers "F.Cu" "F.Mask" "F.Paste")
			(net "DRV_ACT_18")
		)
		(pad "2" smd rect
			(at -0.50038 -0.73025)
			(size 0.7112 0.8636)
			(layers "F.Cu" "F.Mask" "F.Paste")
			(net "FLT_HDD18")
		)
		(pad "3" smd rect
			(at 0.50038 0.73025)
			(size 0.7112 0.8636)
			(layers "F.Cu" "F.Mask" "F.Paste")
			(net "DRV_ACT_18_N")
		)
		(pad "4" smd rect
			(at -0.50038 0.73025)
			(size 0.7112 0.8636)
			(layers "F.Cu" "F.Mask" "F.Paste")
			(net "FLT_HDD18_N")
		)
	)
	(footprint ""
		(layer "F.Cu")
		(at 37.305996 -371.856 -90)
		(property "Reference" "D37"
			(at 0 0 270)
			(layer "F.SilkS")
			(hide yes)
			(effects
				(font
					(size 1.27 1.27)
				)
			)
		)
		(property "Value" "BAS16H-GP"
			(at 0 -5.5372 270)
			(unlocked yes)
			(layer "F.Fab")
			(hide yes)
			(effects
				(font
					(size 1.016 1.016)
					(thickness 0.1524)
				)
			)
		)
		(property "Device Type" "SOD123AKH48"
			(at 0 -7.0612 270)
			(unlocked yes)
			(layer "F.Fab")
			(hide yes)
			(effects
				(font
					(size 1.016 1.016)
					(thickness 0.1524)
				)
			)
		)
		(duplicate_pad_numbers_are_jumpers no)
		(fp_line
			(start 0.889 2.921)
			(end -0.889 2.921)
			(stroke
				(width 0.508)
				(type default)
			)
			(layer "F.SilkS")
		)
		(fp_line
			(start -1.016 2.667)
			(end 1.016 2.667)
			(stroke
				(width 0.1524)
				(type default)
			)
			(layer "F.SilkS")
		)
		(fp_line
			(start 1.016 2.667)
			(end 1.016 -2.667)
			(stroke
				(width 0.1524)
				(type default)
			)
			(layer "F.SilkS")
		)
		(fp_line
			(start -1.016 -2.667)
			(end -1.016 2.667)
			(stroke
				(width 0.1524)
				(type default)
			)
			(layer "F.SilkS")
		)
		(fp_line
			(start 1.016 -2.667)
			(end -1.016 -2.667)
			(stroke
				(width 0.1524)
				(type default)
			)
			(layer "F.SilkS")
		)
		(fp_rect
			(start -1.143 3.175)
			(end 1.143 -2.794)
			(stroke
				(width 0)
				(type default)
			)
			(fill no)
			(layer "F.CrtYd")
		)
		(fp_poly
			(pts
				(xy -1.143 -2.794) (xy 1.143 -2.794) (xy 1.143 3.175) (xy -1.143 3.175)
			)
			(stroke
				(width 0)
				(type default)
			)
			(fill no)
			(layer "F.Fab")
		)
		(pad "A" smd rect
			(at 0 -1.6891 270)
			(size 0.889 1.397)
			(layers "F.Cu" "F.Mask" "F.Paste")
			(net "FAN_0_TACH0")
		)
		(pad "K" smd rect
			(at 0 1.6891 270)
			(size 0.889 1.397)
			(layers "F.Cu" "F.Mask" "F.Paste")
			(net "P12V_IN")
		)
	)
	(footprint ""
		(layer "F.Cu")
		(at 111.379 -138.049 90)
		(property "Reference" "R422"
			(at 0 0 90)
			(layer "F.SilkS")
			(hide yes)
			(effects
				(font
					(size 1.27 1.27)
				)
			)
		)
		(property "Value" "4K7R2J-2-GP"
			(at 0.064008 -3.993896 90)
			(unlocked yes)
			(layer "F.Fab")
			(hide yes)
			(effects
				(font
					(size 1.016 1.016)
					(thickness 0.1524)
				)
			)
		)
		(property "Device Type" "R402H16"
			(at 0.064008 -5.517896 90)
			(unlocked yes)
			(layer "F.Fab")
			(hide yes)
			(effects
				(font
					(size 1.016 1.016)
					(thickness 0.1524)
				)
			)
		)
		(duplicate_pad_numbers_are_jumpers no)
		(fp_line
			(start 0.508 -0.9398)
			(end -0.508 -0.9398)
			(stroke
				(width 0.1524)
				(type default)
			)
			(layer "F.SilkS")
		)
		(fp_line
			(start -0.508 -0.9398)
			(end -0.508 0.9398)
			(stroke
				(width 0.1524)
				(type default)
			)
			(layer "F.SilkS")
		)
		(fp_rect
			(start -0.508 0.9398)
			(end 0.508 -0.9398)
			(stroke
				(width 0)
				(type default)
			)
			(fill no)
			(layer "F.CrtYd")
		)
		(fp_rect
			(start -0.508 0.9398)
			(end 0.508 -0.9398)
			(stroke
				(width 0)
				(type default)
			)
			(fill no)
			(layer "F.Fab")
		)
		(pad "1" smd custom
			(at 0 -0.4445 90)
			(size 0.1397 0.1397)
			(layers "F.Cu" "F.Mask" "F.Paste")
			(net "P12V_B")
			(options
				(clearance outline)
				(anchor circle)
			)
			(primitives
				(gr_poly
					(pts
						(arc
							(start -0.1778 -0.2794)
							(mid -0.249642 -0.249642)
							(end -0.2794 -0.1778)
						)
						(arc
							(start -0.2794 0.1778)
							(mid -0.249642 0.249642)
							(end -0.1778 0.2794)
						)
						(arc
							(start 0.1778 0.2794)
							(mid 0.249642 0.249642)
							(end 0.2794 0.1778)
						)
						(arc
							(start 0.2794 -0.1778)
							(mid 0.249642 -0.249642)
							(end 0.1778 -0.2794)
						)
					)
					(width 0)
					(fill yes)
				)
			)
		)
		(pad "2" smd custom
			(at 0 0.4445 90)
			(size 0.1397 0.1397)
			(layers "F.Cu" "F.Mask" "F.Paste")
			(net "SW_HDD_P15")
			(options
				(clearance outline)
				(anchor circle)
			)
			(primitives
				(gr_poly
					(pts
						(arc
							(start -0.1778 -0.2794)
							(mid -0.249642 -0.249642)
							(end -0.2794 -0.1778)
						)
						(arc
							(start -0.2794 0.1778)
							(mid -0.249642 0.249642)
							(end -0.1778 0.2794)
						)
						(arc
							(start 0.1778 0.2794)
							(mid 0.249642 0.249642)
							(end 0.2794 0.1778)
						)
						(arc
							(start 0.2794 -0.1778)
							(mid 0.249642 -0.249642)
							(end 0.1778 -0.2794)
						)
					)
					(width 0)
					(fill yes)
				)
			)
		)
	)
)
